(kicad_pcb
	(version 20260206)
	(generator "pcbnew")
	(generator_version "10.0")
	(general
		(thickness 1.6)
		(legacy_teardrops no)
	)
	(paper "A4")
	(title_block
		(title "04192023_DAF0TMB3IC0_F0TG_MB_C_brd_V02_OCP.brd")
		(comment 1 "Grand Teton / footprints 1161-1167 of 8354")
	)
	(layers
		(0 "F.Cu" signal "TOP")
		(4 "In1.Cu" signal "GND")
		(6 "In2.Cu" signal "IN1")
		(8 "In3.Cu" signal "GND1")
		(10 "In4.Cu" signal "IN2")
		(12 "In5.Cu" signal "GND2")
		(14 "In6.Cu" signal "IN3")
		(16 "In7.Cu" signal "GND3")
		(18 "In8.Cu" signal "VCC")
		(20 "In9.Cu" signal "VCC1")
		(22 "In10.Cu" signal "GND4")
		(24 "In11.Cu" signal "IN4")
		(26 "In12.Cu" signal "GND5")
		(28 "In13.Cu" signal "IN5")
		(30 "In14.Cu" signal "GND6")
		(32 "In15.Cu" signal "IN6")
		(34 "In16.Cu" signal "GND7")
		(2 "B.Cu" signal "BOTTOM")
		(9 "F.Adhes" user "F.Adhesive")
		(11 "B.Adhes" user "B.Adhesive")
		(13 "F.Paste" user "Package Geometry/Pastemask Top")
		(15 "B.Paste" user "Package Geometry/Pastemask Bottom")
		(5 "F.SilkS" user "Ref Des/Silkscreen Top")
		(7 "B.SilkS" user "Ref Des/Silkscreen Bottom")
		(1 "F.Mask" user "Board Geometry/Soldermask Top")
		(3 "B.Mask" user "Board Geometry/Soldermask Bottom")
		(17 "Dwgs.User" user "User.Drawings")
		(19 "Cmts.User" user "User.Comments")
		(21 "Eco1.User" user "User.Eco1")
		(23 "Eco2.User" user "User.Eco2")
		(25 "Edge.Cuts" user "Board Geometry/Outline")
		(27 "Margin" user)
		(31 "F.CrtYd" user "Package Geometry/Place Bound Top")
		(29 "B.CrtYd" user "Package Geometry/Place Bound Bottom")
		(35 "F.Fab" user "Ref Des/Assembly Top")
		(33 "B.Fab" user "Ref Des/Assembly Bottom")
	)
	(footprint ""
		(layer "F.Cu")
		(at 302.344836 -422.967404 90)
		(property "Reference" "C7510"
			(at 0 0 90)
			(layer "F.SilkS")
			(hide yes)
			(effects
				(font
					(size 1.27 1.27)
				)
			)
		)
		(property "Value" ""
			(at 0 0 90)
			(layer "F.Fab")
			(effects
				(font
					(size 1.27 1.27)
				)
			)
		)
		(duplicate_pad_numbers_are_jumpers no)
		(fp_line
			(start 0.299974 -0.150114)
			(end 0.299974 0.150114)
			(stroke
				(width 0.1)
				(type default)
			)
			(layer "F.Fab")
		)
		(fp_line
			(start -0.299974 -0.150114)
			(end 0.299974 -0.150114)
			(stroke
				(width 0.1)
				(type default)
			)
			(layer "F.Fab")
		)
		(fp_line
			(start 0.299974 0.150114)
			(end -0.299974 0.150114)
			(stroke
				(width 0.1)
				(type default)
			)
			(layer "F.Fab")
		)
		(fp_line
			(start -0.299974 0.150114)
			(end -0.299974 -0.150114)
			(stroke
				(width 0.1)
				(type default)
			)
			(layer "F.Fab")
		)
		(pad "1" smd rect
			(at -0.2667 0 90)
			(size 0.3048 0.381)
			(layers "F.Cu" "F.Mask" "F.Paste")
			(net "P1V8_CPU0_RT_1D")
		)
		(pad "2" smd rect
			(at 0.2667 0 90)
			(size 0.3048 0.381)
			(layers "F.Cu" "F.Mask" "F.Paste")
			(net "GND")
		)
	)
	(footprint ""
		(layer "F.Cu")
		(at 100.151184 -35.30092)
		(property "Reference" "R3192"
			(at 0 0 0)
			(layer "F.SilkS")
			(hide yes)
			(effects
				(font
					(size 1.27 1.27)
				)
			)
		)
		(property "Value" ""
			(at 0 0 0)
			(layer "F.Fab")
			(effects
				(font
					(size 1.27 1.27)
				)
			)
		)
		(duplicate_pad_numbers_are_jumpers no)
		(fp_line
			(start -0.7874 -0.4064)
			(end 0.7874 -0.4064)
			(stroke
				(width 0.1524)
				(type default)
			)
			(layer "F.SilkS")
		)
		(fp_line
			(start -0.7874 0.4064)
			(end -0.7874 -0.4064)
			(stroke
				(width 0.1524)
				(type default)
			)
			(layer "F.SilkS")
		)
		(fp_line
			(start 0.7874 -0.4064)
			(end 0.7874 0.4064)
			(stroke
				(width 0.1524)
				(type default)
			)
			(layer "F.SilkS")
		)
		(fp_line
			(start 0.7874 0.4064)
			(end -0.7874 0.4064)
			(stroke
				(width 0.1524)
				(type default)
			)
			(layer "F.SilkS")
		)
		(fp_line
			(start -0.67945 -0.305054)
			(end -0.12065 -0.305054)
			(stroke
				(width 0.1)
				(type default)
			)
			(layer "F.Fab")
		)
		(fp_line
			(start -0.67945 0.3048)
			(end -0.67945 -0.305054)
			(stroke
				(width 0.1)
				(type default)
			)
			(layer "F.Fab")
		)
		(fp_line
			(start -0.12065 -0.305054)
			(end -0.12065 -0.2794)
			(stroke
				(width 0.1)
				(type default)
			)
			(layer "F.Fab")
		)
		(fp_line
			(start -0.12065 -0.2794)
			(end 0.12065 -0.2794)
			(stroke
				(width 0.1)
				(type default)
			)
			(layer "F.Fab")
		)
		(fp_line
			(start -0.12065 0.2794)
			(end -0.12065 0.3048)
			(stroke
				(width 0.1)
				(type default)
			)
			(layer "F.Fab")
		)
		(fp_line
			(start -0.12065 0.3048)
			(end -0.67945 0.3048)
			(stroke
				(width 0.1)
				(type default)
			)
			(layer "F.Fab")
		)
		(fp_line
			(start 0.120396 0.2794)
			(end -0.12065 0.2794)
			(stroke
				(width 0.1)
				(type default)
			)
			(layer "F.Fab")
		)
		(fp_line
			(start 0.120396 0.3048)
			(end 0.120396 0.2794)
			(stroke
				(width 0.1)
				(type default)
			)
			(layer "F.Fab")
		)
		(fp_line
			(start 0.12065 -0.3048)
			(end 0.67945 -0.3048)
			(stroke
				(width 0.1)
				(type default)
			)
			(layer "F.Fab")
		)
		(fp_line
			(start 0.12065 -0.2794)
			(end 0.12065 -0.3048)
			(stroke
				(width 0.1)
				(type default)
			)
			(layer "F.Fab")
		)
		(fp_line
			(start 0.67945 -0.3048)
			(end 0.67945 0.3048)
			(stroke
				(width 0.1)
				(type default)
			)
			(layer "F.Fab")
		)
		(fp_line
			(start 0.67945 0.3048)
			(end 0.120396 0.3048)
			(stroke
				(width 0.1)
				(type default)
			)
			(layer "F.Fab")
		)
		(pad "1" smd circle
			(at -0.40005 0)
			(size 0 0)
			(layers "F.Cu" "F.Mask" "F.Paste")
			(net "P3V3_AUX")
		)
		(pad "2" smd circle
			(at 0.40005 0)
			(size 0 0)
			(layers "F.Cu" "F.Mask" "F.Paste")
			(net "IRQ_LVC3_V3_2_WAKE_BUF_N")
		)
	)
	(footprint ""
		(layer "F.Cu")
		(at 394.067284 -390.1694)
		(property "Reference" "R1412"
			(at 0 0 0)
			(layer "F.SilkS")
			(hide yes)
			(effects
				(font
					(size 1.27 1.27)
				)
			)
		)
		(property "Value" ""
			(at 0 0 0)
			(layer "F.Fab")
			(effects
				(font
					(size 1.27 1.27)
				)
			)
		)
		(duplicate_pad_numbers_are_jumpers no)
		(fp_line
			(start -0.32512 -0.175006)
			(end 0.32512 -0.175006)
			(stroke
				(width 0.1)
				(type default)
			)
			(layer "F.Fab")
		)
		(fp_line
			(start -0.32512 0.175006)
			(end -0.32512 -0.175006)
			(stroke
				(width 0.1)
				(type default)
			)
			(layer "F.Fab")
		)
		(fp_line
			(start 0.32512 -0.175006)
			(end 0.32512 0.175006)
			(stroke
				(width 0.1)
				(type default)
			)
			(layer "F.Fab")
		)
		(fp_line
			(start 0.32512 0.175006)
			(end -0.32512 0.175006)
			(stroke
				(width 0.1)
				(type default)
			)
			(layer "F.Fab")
		)
		(pad "1" smd rect
			(at -0.2667 0)
			(size 0.3048 0.381)
			(layers "F.Cu" "F.Mask" "F.Paste")
			(net "CLKREQ_RT_CPU0_P3_N")
		)
		(pad "2" smd rect
			(at 0.2667 0 180)
			(size 0.3048 0.381)
			(layers "F.Cu" "F.Mask" "F.Paste")
			(net "GND")
		)
	)
	(footprint ""
		(layer "F.Cu")
		(at 206.4385 -402.191982 90)
		(property "Reference" "PC2181"
			(at 0 0 90)
			(layer "F.SilkS")
			(hide yes)
			(effects
				(font
					(size 1.27 1.27)
				)
			)
		)
		(property "Value" ""
			(at 0 0 90)
			(layer "F.Fab")
			(effects
				(font
					(size 1.27 1.27)
				)
			)
		)
		(duplicate_pad_numbers_are_jumpers no)
		(fp_line
			(start 0.7874 -0.4064)
			(end 0.7874 0.4064)
			(stroke
				(width 0.1524)
				(type default)
			)
			(layer "F.SilkS")
		)
		(fp_line
			(start -0.7874 -0.4064)
			(end 0.7874 -0.4064)
			(stroke
				(width 0.1524)
				(type default)
			)
			(layer "F.SilkS")
		)
		(fp_line
			(start 0.7874 0.4064)
			(end -0.7874 0.4064)
			(stroke
				(width 0.1524)
				(type default)
			)
			(layer "F.SilkS")
		)
		(fp_line
			(start -0.7874 0.4064)
			(end -0.7874 -0.4064)
			(stroke
				(width 0.1524)
				(type default)
			)
			(layer "F.SilkS")
		)
		(fp_line
			(start -0.12065 -0.305054)
			(end -0.12065 -0.2794)
			(stroke
				(width 0.1)
				(type default)
			)
			(layer "F.Fab")
		)
		(fp_line
			(start -0.67945 -0.305054)
			(end -0.12065 -0.305054)
			(stroke
				(width 0.1)
				(type default)
			)
			(layer "F.Fab")
		)
		(fp_line
			(start 0.67945 -0.3048)
			(end 0.67945 0.3048)
			(stroke
				(width 0.1)
				(type default)
			)
			(layer "F.Fab")
		)
		(fp_line
			(start 0.12065 -0.3048)
			(end 0.67945 -0.3048)
			(stroke
				(width 0.1)
				(type default)
			)
			(layer "F.Fab")
		)
		(fp_line
			(start 0.12065 -0.2794)
			(end 0.12065 -0.3048)
			(stroke
				(width 0.1)
				(type default)
			)
			(layer "F.Fab")
		)
		(fp_line
			(start -0.12065 -0.2794)
			(end 0.12065 -0.2794)
			(stroke
				(width 0.1)
				(type default)
			)
			(layer "F.Fab")
		)
		(fp_line
			(start 0.120396 0.2794)
			(end -0.12065 0.2794)
			(stroke
				(width 0.1)
				(type default)
			)
			(layer "F.Fab")
		)
		(fp_line
			(start -0.12065 0.2794)
			(end -0.12065 0.3048)
			(stroke
				(width 0.1)
				(type default)
			)
			(layer "F.Fab")
		)
		(fp_line
			(start 0.67945 0.3048)
			(end 0.120396 0.3048)
			(stroke
				(width 0.1)
				(type default)
			)
			(layer "F.Fab")
		)
		(fp_line
			(start 0.120396 0.3048)
			(end 0.120396 0.2794)
			(stroke
				(width 0.1)
				(type default)
			)
			(layer "F.Fab")
		)
		(fp_line
			(start -0.12065 0.3048)
			(end -0.67945 0.3048)
			(stroke
				(width 0.1)
				(type default)
			)
			(layer "F.Fab")
		)
		(fp_line
			(start -0.67945 0.3048)
			(end -0.67945 -0.305054)
			(stroke
				(width 0.1)
				(type default)
			)
			(layer "F.Fab")
		)
		(pad "1" smd circle
			(at -0.40005 0 90)
			(size 0 0)
			(layers "F.Cu" "F.Mask" "F.Paste")
			(net "HSC_VDD_R_2")
		)
		(pad "2" smd circle
			(at 0.40005 0 90)
			(size 0 0)
			(layers "F.Cu" "F.Mask" "F.Paste")
			(net "AGND_HSC")
		)
	)
	(footprint ""
		(layer "F.Cu")
		(at 90.75674 -335.128616 -90)
		(property "Reference" "PC377_1"
			(at 0 0 270)
			(layer "F.SilkS")
			(hide yes)
			(effects
				(font
					(size 1.27 1.27)
				)
			)
		)
		(property "Value" ""
			(at 0 0 270)
			(layer "F.Fab")
			(effects
				(font
					(size 1.27 1.27)
				)
			)
		)
		(duplicate_pad_numbers_are_jumpers no)
		(fp_line
			(start -0.7874 0.4064)
			(end -0.7874 -0.4064)
			(stroke
				(width 0.1524)
				(type default)
			)
			(layer "F.SilkS")
		)
		(fp_line
			(start 0.7874 0.4064)
			(end -0.7874 0.4064)
			(stroke
				(width 0.1524)
				(type default)
			)
			(layer "F.SilkS")
		)
		(fp_line
			(start -0.7874 -0.4064)
			(end 0.7874 -0.4064)
			(stroke
				(width 0.1524)
				(type default)
			)
			(layer "F.SilkS")
		)
		(fp_line
			(start 0.7874 -0.4064)
			(end 0.7874 0.4064)
			(stroke
				(width 0.1524)
				(type default)
			)
			(layer "F.SilkS")
		)
		(fp_line
			(start -0.67945 0.3048)
			(end -0.67945 -0.305054)
			(stroke
				(width 0.1)
				(type default)
			)
			(layer "F.Fab")
		)
		(fp_line
			(start -0.12065 0.3048)
			(end -0.67945 0.3048)
			(stroke
				(width 0.1)
				(type default)
			)
			(layer "F.Fab")
		)
		(fp_line
			(start 0.120396 0.3048)
			(end 0.120396 0.2794)
			(stroke
				(width 0.1)
				(type default)
			)
			(layer "F.Fab")
		)
		(fp_line
			(start 0.67945 0.3048)
			(end 0.120396 0.3048)
			(stroke
				(width 0.1)
				(type default)
			)
			(layer "F.Fab")
		)
		(fp_line
			(start -0.12065 0.2794)
			(end -0.12065 0.3048)
			(stroke
				(width 0.1)
				(type default)
			)
			(layer "F.Fab")
		)
		(fp_line
			(start 0.120396 0.2794)
			(end -0.12065 0.2794)
			(stroke
				(width 0.1)
				(type default)
			)
			(layer "F.Fab")
		)
		(fp_line
			(start -0.12065 -0.2794)
			(end 0.12065 -0.2794)
			(stroke
				(width 0.1)
				(type default)
			)
			(layer "F.Fab")
		)
		(fp_line
			(start 0.12065 -0.2794)
			(end 0.12065 -0.3048)
			(stroke
				(width 0.1)
				(type default)
			)
			(layer "F.Fab")
		)
		(fp_line
			(start 0.12065 -0.3048)
			(end 0.67945 -0.3048)
			(stroke
				(width 0.1)
				(type default)
			)
			(layer "F.Fab")
		)
		(fp_line
			(start 0.67945 -0.3048)
			(end 0.67945 0.3048)
			(stroke
				(width 0.1)
				(type default)
			)
			(layer "F.Fab")
		)
		(fp_line
			(start -0.67945 -0.305054)
			(end -0.12065 -0.305054)
			(stroke
				(width 0.1)
				(type default)
			)
			(layer "F.Fab")
		)
		(fp_line
			(start -0.12065 -0.305054)
			(end -0.12065 -0.2794)
			(stroke
				(width 0.1)
				(type default)
			)
			(layer "F.Fab")
		)
		(pad "1" smd circle
			(at -0.40005 0 270)
			(size 0 0)
			(layers "F.Cu" "F.Mask" "F.Paste")
			(net "SW_P12V_AUX_PVDDCR_CPU1_P1_FLT")
		)
		(pad "2" smd circle
			(at 0.40005 0 270)
			(size 0 0)
			(layers "F.Cu" "F.Mask" "F.Paste")
			(net "GND")
		)
	)
	(footprint ""
		(layer "F.Cu")
		(at 15.094458 -418.690298 -90)
		(property "Reference" "R6178"
			(at 0 0 270)
			(layer "F.SilkS")
			(hide yes)
			(effects
				(font
					(size 1.27 1.27)
				)
			)
		)
		(property "Value" ""
			(at 0 0 270)
			(layer "F.Fab")
			(effects
				(font
					(size 1.27 1.27)
				)
			)
		)
		(duplicate_pad_numbers_are_jumpers no)
		(fp_line
			(start -0.7874 0.4064)
			(end -0.7874 -0.4064)
			(stroke
				(width 0.1524)
				(type default)
			)
			(layer "F.SilkS")
		)
		(fp_line
			(start 0.7874 0.4064)
			(end -0.7874 0.4064)
			(stroke
				(width 0.1524)
				(type default)
			)
			(layer "F.SilkS")
		)
		(fp_line
			(start -0.7874 -0.4064)
			(end 0.7874 -0.4064)
			(stroke
				(width 0.1524)
				(type default)
			)
			(layer "F.SilkS")
		)
		(fp_line
			(start 0.7874 -0.4064)
			(end 0.7874 0.4064)
			(stroke
				(width 0.1524)
				(type default)
			)
			(layer "F.SilkS")
		)
		(fp_line
			(start -0.67945 0.3048)
			(end -0.67945 -0.305054)
			(stroke
				(width 0.1)
				(type default)
			)
			(layer "F.Fab")
		)
		(fp_line
			(start -0.12065 0.3048)
			(end -0.67945 0.3048)
			(stroke
				(width 0.1)
				(type default)
			)
			(layer "F.Fab")
		)
		(fp_line
			(start 0.120396 0.3048)
			(end 0.120396 0.2794)
			(stroke
				(width 0.1)
				(type default)
			)
			(layer "F.Fab")
		)
		(fp_line
			(start 0.67945 0.3048)
			(end 0.120396 0.3048)
			(stroke
				(width 0.1)
				(type default)
			)
			(layer "F.Fab")
		)
		(fp_line
			(start -0.12065 0.2794)
			(end -0.12065 0.3048)
			(stroke
				(width 0.1)
				(type default)
			)
			(layer "F.Fab")
		)
		(fp_line
			(start 0.120396 0.2794)
			(end -0.12065 0.2794)
			(stroke
				(width 0.1)
				(type default)
			)
			(layer "F.Fab")
		)
		(fp_line
			(start -0.12065 -0.2794)
			(end 0.12065 -0.2794)
			(stroke
				(width 0.1)
				(type default)
			)
			(layer "F.Fab")
		)
		(fp_line
			(start 0.12065 -0.2794)
			(end 0.12065 -0.3048)
			(stroke
				(width 0.1)
				(type default)
			)
			(layer "F.Fab")
		)
		(fp_line
			(start 0.12065 -0.3048)
			(end 0.67945 -0.3048)
			(stroke
				(width 0.1)
				(type default)
			)
			(layer "F.Fab")
		)
		(fp_line
			(start 0.67945 -0.3048)
			(end 0.67945 0.3048)
			(stroke
				(width 0.1)
				(type default)
			)
			(layer "F.Fab")
		)
		(fp_line
			(start -0.67945 -0.305054)
			(end -0.12065 -0.305054)
			(stroke
				(width 0.1)
				(type default)
			)
			(layer "F.Fab")
		)
		(fp_line
			(start -0.12065 -0.305054)
			(end -0.12065 -0.2794)
			(stroke
				(width 0.1)
				(type default)
			)
			(layer "F.Fab")
		)
		(pad "1" smd circle
			(at -0.40005 0 270)
			(size 0 0)
			(layers "F.Cu" "F.Mask" "F.Paste")
			(net "FM_P2E_BUF2_SD_TH")
		)
		(pad "2" smd circle
			(at 0.40005 0 270)
			(size 0 0)
			(layers "F.Cu" "F.Mask" "F.Paste")
			(net "GND")
		)
	)
	(footprint ""
		(layer "F.Cu")
		(at 203.310744 -346.505022 180)
		(property "Reference" "PL71"
			(at 0 0 180)
			(layer "F.SilkS")
			(hide yes)
			(effects
				(font
					(size 1.27 1.27)
				)
			)
		)
		(property "Value" ""
			(at 0 0 180)
			(layer "F.Fab")
			(effects
				(font
					(size 1.27 1.27)
				)
			)
		)
		(duplicate_pad_numbers_are_jumpers no)
		(fp_line
			(start 1.27 0.5842)
			(end 1.27 -0.5842)
			(stroke
				(width 0.1524)
				(type default)
			)
			(layer "F.SilkS")
		)
		(fp_line
			(start 1.27 0.5842)
			(end -1.27 0.5842)
			(stroke
				(width 0.1524)
				(type default)
			)
			(layer "F.SilkS")
		)
		(fp_line
			(start -1.27 0.5842)
			(end -1.27 -0.5842)
			(stroke
				(width 0.1524)
				(type default)
			)
			(layer "F.SilkS")
		)
		(fp_line
			(start -1.27 -0.5588)
			(end -1.27 -0.5842)
			(stroke
				(width 0.1524)
				(type default)
			)
			(layer "F.SilkS")
		)
		(fp_line
			(start -1.27 -0.5842)
			(end 1.27 -0.5842)
			(stroke
				(width 0.1524)
				(type default)
			)
			(layer "F.SilkS")
		)
		(fp_line
			(start 1.1938 0.4064)
			(end 0.9144 0.4064)
			(stroke
				(width 0.1)
				(type default)
			)
			(layer "F.Fab")
		)
		(fp_line
			(start 1.1938 -0.406654)
			(end 1.1938 0.4064)
			(stroke
				(width 0.1)
				(type default)
			)
			(layer "F.Fab")
		)
		(fp_line
			(start 0.9144 0.508)
			(end -0.9144 0.508)
			(stroke
				(width 0.1)
				(type default)
			)
			(layer "F.Fab")
		)
		(fp_line
			(start 0.9144 0.4064)
			(end 0.9144 0.508)
			(stroke
				(width 0.1)
				(type default)
			)
			(layer "F.Fab")
		)
		(fp_line
			(start 0.9144 -0.406654)
			(end 1.1938 -0.406654)
			(stroke
				(width 0.1)
				(type default)
			)
			(layer "F.Fab")
		)
		(fp_line
			(start 0.9144 -0.508)
			(end 0.9144 -0.406654)
			(stroke
				(width 0.1)
				(type default)
			)
			(layer "F.Fab")
		)
		(fp_line
			(start -0.9144 0.508)
			(end -0.9144 0.406654)
			(stroke
				(width 0.1)
				(type default)
			)
			(layer "F.Fab")
		)
		(fp_line
			(start -0.9144 0.406654)
			(end -1.194308 0.406654)
			(stroke
				(width 0.1)
				(type default)
			)
			(layer "F.Fab")
		)
		(fp_line
			(start -0.9144 -0.406654)
			(end -0.9144 -0.508)
			(stroke
				(width 0.1)
				(type default)
			)
			(layer "F.Fab")
		)
		(fp_line
			(start -0.9144 -0.508)
			(end 0.9144 -0.508)
			(stroke
				(width 0.1)
				(type default)
			)
			(layer "F.Fab")
		)
		(fp_line
			(start -1.194308 0.406654)
			(end -1.194308 -0.406654)
			(stroke
				(width 0.1)
				(type default)
			)
			(layer "F.Fab")
		)
		(fp_line
			(start -1.194308 -0.406654)
			(end -0.9144 -0.406654)
			(stroke
				(width 0.1)
				(type default)
			)
			(layer "F.Fab")
		)
		(pad "1" smd rect
			(at -0.7366 0 90)
			(size 0.7112 0.8128)
			(layers "F.Cu" "F.Mask" "F.Paste")
			(net "P12V_AUX")
		)
		(pad "2" smd rect
			(at 0.7366 0 90)
			(size 0.7112 0.8128)
			(layers "F.Cu" "F.Mask" "F.Paste")
			(net "SW_P12V_AUX_PVDD_33_S5_FLT")
		)
	)
)
